# T6G (Grand Teton) — schematic netlist excerpt (pin names and nets, part order shuffled) for the footprints in the layout excerpt that follows; sources: Cadence DE-HDL packaged netlist, KiCad conversion of 04192023_DAF0TMB3IC0_F0TG_MB_C_brd_V02_OCP.brd

C2254  Q_CAP  22UF 4V 20% X6S  pkg C0402  page 69 : A = PVDDCR_CPU1_P0 ; B = GND
PC108_2  Q_CAP  22UF 4V 20% X6S  pkg C0805  page 201 : A = PVDDCR_CPU1_P0 ; B = GND
C969  Q_CAP  22UF 4V 20% X6S  pkg C0402  page 301 : A = P0V9_CPU0_RT2_2A ; B = GND

(kicad_pcb
	(version 20260206)
	(generator "pcbnew")
	(generator_version "10.0")
	(general
		(thickness 1.6)
		(legacy_teardrops no)
	)
	(paper "A4")
	(title_block
		(title "04192023_DAF0TMB3IC0_F0TG_MB_C_brd_V02_OCP.brd")
		(comment 1 "Grand Teton / footprints 4989-4991 of 8354")
	)
	(layers
		(0 "F.Cu" signal "TOP")
		(4 "In1.Cu" signal "GND")
		(6 "In2.Cu" signal "IN1")
		(8 "In3.Cu" signal "GND1")
		(10 "In4.Cu" signal "IN2")
		(12 "In5.Cu" signal "GND2")
		(14 "In6.Cu" signal "IN3")
		(16 "In7.Cu" signal "GND3")
		(18 "In8.Cu" signal "VCC")
		(20 "In9.Cu" signal "VCC1")
		(22 "In10.Cu" signal "GND4")
		(24 "In11.Cu" signal "IN4")
		(26 "In12.Cu" signal "GND5")
		(28 "In13.Cu" signal "IN5")
		(30 "In14.Cu" signal "GND6")
		(32 "In15.Cu" signal "IN6")
		(34 "In16.Cu" signal "GND7")
		(2 "B.Cu" signal "BOTTOM")
		(9 "F.Adhes" user "F.Adhesive")
		(11 "B.Adhes" user "B.Adhesive")
		(13 "F.Paste" user "Package Geometry/Pastemask Top")
		(15 "B.Paste" user "Package Geometry/Pastemask Bottom")
		(5 "F.SilkS" user "Ref Des/Silkscreen Top")
		(7 "B.SilkS" user "Ref Des/Silkscreen Bottom")
		(1 "F.Mask" user "Board Geometry/Soldermask Top")
		(3 "B.Mask" user "Board Geometry/Soldermask Bottom")
		(17 "Dwgs.User" user "User.Drawings")
		(19 "Cmts.User" user "User.Comments")
		(21 "Eco1.User" user "User.Eco1")
		(23 "Eco2.User" user "User.Eco2")
		(25 "Edge.Cuts" user "Board Geometry/Outline")
		(27 "Margin" user)
		(31 "F.CrtYd" user "Package Geometry/Place Bound Top")
		(29 "B.CrtYd" user "Package Geometry/Place Bound Bottom")
		(35 "F.Fab" user "Ref Des/Assembly Top")
		(33 "B.Fab" user "Ref Des/Assembly Bottom")
	)
	(footprint ""
		(layer "B.Cu")
		(at 418.618924 -398.942052 90)
		(property "Reference" "C969"
			(at 0 0 90)
			(layer "B.SilkS")
			(hide yes)
			(effects
				(font
					(size 1.27 1.27)
				)
				(justify mirror)
			)
		)
		(property "Value" ""
			(at 0 0 90)
			(layer "B.Fab")
			(effects
				(font
					(size 1.27 1.27)
				)
				(justify mirror)
			)
		)
		(duplicate_pad_numbers_are_jumpers no)
		(fp_line
			(start 0.7874 -0.4064)
			(end -0.7874 -0.4064)
			(stroke
				(width 0.1524)
				(type default)
			)
			(layer "B.SilkS")
		)
		(fp_line
			(start -0.7874 -0.4064)
			(end -0.7874 0.4064)
			(stroke
				(width 0.1524)
				(type default)
			)
			(layer "B.SilkS")
		)
		(fp_line
			(start 0.7874 0.4064)
			(end 0.7874 -0.4064)
			(stroke
				(width 0.1524)
				(type default)
			)
			(layer "B.SilkS")
		)
		(fp_line
			(start -0.7874 0.4064)
			(end 0.7874 0.4064)
			(stroke
				(width 0.1524)
				(type default)
			)
			(layer "B.SilkS")
		)
		(fp_line
			(start 0.67945 -0.305054)
			(end 0.12065 -0.305054)
			(stroke
				(width 0.1)
				(type default)
			)
			(layer "B.Fab")
		)
		(fp_line
			(start 0.12065 -0.305054)
			(end 0.12065 -0.2794)
			(stroke
				(width 0.1)
				(type default)
			)
			(layer "B.Fab")
		)
		(fp_line
			(start -0.12065 -0.3048)
			(end -0.67945 -0.3048)
			(stroke
				(width 0.1)
				(type default)
			)
			(layer "B.Fab")
		)
		(fp_line
			(start -0.67945 -0.3048)
			(end -0.67945 0.3048)
			(stroke
				(width 0.1)
				(type default)
			)
			(layer "B.Fab")
		)
		(fp_line
			(start 0.12065 -0.2794)
			(end -0.12065 -0.2794)
			(stroke
				(width 0.1)
				(type default)
			)
			(layer "B.Fab")
		)
		(fp_line
			(start -0.12065 -0.2794)
			(end -0.12065 -0.3048)
			(stroke
				(width 0.1)
				(type default)
			)
			(layer "B.Fab")
		)
		(fp_line
			(start 0.12065 0.2794)
			(end 0.12065 0.3048)
			(stroke
				(width 0.1)
				(type default)
			)
			(layer "B.Fab")
		)
		(fp_line
			(start -0.120396 0.2794)
			(end 0.12065 0.2794)
			(stroke
				(width 0.1)
				(type default)
			)
			(layer "B.Fab")
		)
		(fp_line
			(start 0.67945 0.3048)
			(end 0.67945 -0.305054)
			(stroke
				(width 0.1)
				(type default)
			)
			(layer "B.Fab")
		)
		(fp_line
			(start 0.12065 0.3048)
			(end 0.67945 0.3048)
			(stroke
				(width 0.1)
				(type default)
			)
			(layer "B.Fab")
		)
		(fp_line
			(start -0.120396 0.3048)
			(end -0.120396 0.2794)
			(stroke
				(width 0.1)
				(type default)
			)
			(layer "B.Fab")
		)
		(fp_line
			(start -0.67945 0.3048)
			(end -0.120396 0.3048)
			(stroke
				(width 0.1)
				(type default)
			)
			(layer "B.Fab")
		)
		(pad "1" smd circle
			(at 0.40005 0 270)
			(size 0 0)
			(layers "B.Cu" "B.Mask" "B.Paste")
			(net "P0V9_CPU0_RT2_2A")
		)
		(pad "2" smd circle
			(at -0.40005 0 270)
			(size 0 0)
			(layers "B.Cu" "B.Mask" "B.Paste")
			(net "GND")
		)
	)
	(footprint ""
		(layer "B.Cu")
		(at 322.4149 -326.227186 -90)
		(property "Reference" "PC108_2"
			(at 0 0 90)
			(layer "B.SilkS")
			(hide yes)
			(effects
				(font
					(size 1.27 1.27)
				)
				(justify mirror)
			)
		)
		(property "Value" ""
			(at 0 0 90)
			(layer "B.Fab")
			(effects
				(font
					(size 1.27 1.27)
				)
				(justify mirror)
			)
		)
		(duplicate_pad_numbers_are_jumpers no)
		(fp_line
			(start -1.524 0.762)
			(end 1.524 0.762)
			(stroke
				(width 0.1524)
				(type default)
			)
			(layer "B.SilkS")
		)
		(fp_line
			(start 1.524 0.762)
			(end 1.524 -0.762)
			(stroke
				(width 0.1524)
				(type default)
			)
			(layer "B.SilkS")
		)
		(fp_line
			(start -1.524 -0.762)
			(end -1.524 0.762)
			(stroke
				(width 0.1524)
				(type default)
			)
			(layer "B.SilkS")
		)
		(fp_line
			(start 1.524 -0.762)
			(end -1.524 -0.762)
			(stroke
				(width 0.1524)
				(type default)
			)
			(layer "B.SilkS")
		)
		(fp_line
			(start -1.1049 0.724916)
			(end -1.1049 -0.724916)
			(stroke
				(width 0.1)
				(type default)
			)
			(layer "B.Fab")
		)
		(fp_line
			(start 1.1049 0.724916)
			(end -1.1049 0.724916)
			(stroke
				(width 0.1)
				(type default)
			)
			(layer "B.Fab")
		)
		(fp_line
			(start -1.1049 -0.724916)
			(end 1.1049 -0.724916)
			(stroke
				(width 0.1)
				(type default)
			)
			(layer "B.Fab")
		)
		(fp_line
			(start 1.1049 -0.724916)
			(end 1.1049 0.724916)
			(stroke
				(width 0.1)
				(type default)
			)
			(layer "B.Fab")
		)
		(pad "1" smd rect
			(at 0.889 0 270)
			(size 1.016 1.27)
			(layers "B.Cu" "B.Mask" "B.Paste")
			(net "PVDDCR_CPU1_P0")
		)
		(pad "2" smd rect
			(at -0.889 0 270)
			(size 1.016 1.27)
			(layers "B.Cu" "B.Mask" "B.Paste")
			(net "GND")
		)
	)
	(footprint ""
		(layer "B.Cu")
		(at 364.820454 -269.30731)
		(property "Reference" "C2254"
			(at 0 0 0)
			(layer "B.SilkS")
			(hide yes)
			(effects
				(font
					(size 1.27 1.27)
				)
				(justify mirror)
			)
		)
		(property "Value" ""
			(at 0 0 0)
			(layer "B.Fab")
			(effects
				(font
					(size 1.27 1.27)
				)
				(justify mirror)
			)
		)
		(duplicate_pad_numbers_are_jumpers no)
		(fp_line
			(start -0.7874 -0.4064)
			(end -0.7874 0.4064)
			(stroke
				(width 0.1524)
				(type default)
			)
			(layer "B.SilkS")
		)
		(fp_line
			(start -0.7874 0.4064)
			(end 0.7874 0.4064)
			(stroke
				(width 0.1524)
				(type default)
			)
			(layer "B.SilkS")
		)
		(fp_line
			(start 0.7874 -0.4064)
			(end -0.7874 -0.4064)
			(stroke
				(width 0.1524)
				(type default)
			)
			(layer "B.SilkS")
		)
		(fp_line
			(start 0.7874 0.4064)
			(end 0.7874 -0.4064)
			(stroke
				(width 0.1524)
				(type default)
			)
			(layer "B.SilkS")
		)
		(fp_line
			(start -0.67945 -0.3048)
			(end -0.67945 0.3048)
			(stroke
				(width 0.1)
				(type default)
			)
			(layer "B.Fab")
		)
		(fp_line
			(start -0.67945 0.3048)
			(end -0.120396 0.3048)
			(stroke
				(width 0.1)
				(type default)
			)
			(layer "B.Fab")
		)
		(fp_line
			(start -0.12065 -0.3048)
			(end -0.67945 -0.3048)
			(stroke
				(width 0.1)
				(type default)
			)
			(layer "B.Fab")
		)
		(fp_line
			(start -0.12065 -0.2794)
			(end -0.12065 -0.3048)
			(stroke
				(width 0.1)
				(type default)
			)
			(layer "B.Fab")
		)
		(fp_line
			(start -0.120396 0.2794)
			(end 0.12065 0.2794)
			(stroke
				(width 0.1)
				(type default)
			)
			(layer "B.Fab")
		)
		(fp_line
			(start -0.120396 0.3048)
			(end -0.120396 0.2794)
			(stroke
				(width 0.1)
				(type default)
			)
			(layer "B.Fab")
		)
		(fp_line
			(start 0.12065 -0.305054)
			(end 0.12065 -0.2794)
			(stroke
				(width 0.1)
				(type default)
			)
			(layer "B.Fab")
		)
		(fp_line
			(start 0.12065 -0.2794)
			(end -0.12065 -0.2794)
			(stroke
				(width 0.1)
				(type default)
			)
			(layer "B.Fab")
		)
		(fp_line
			(start 0.12065 0.2794)
			(end 0.12065 0.3048)
			(stroke
				(width 0.1)
				(type default)
			)
			(layer "B.Fab")
		)
		(fp_line
			(start 0.12065 0.3048)
			(end 0.67945 0.3048)
			(stroke
				(width 0.1)
				(type default)
			)
			(layer "B.Fab")
		)
		(fp_line
			(start 0.67945 -0.305054)
			(end 0.12065 -0.305054)
			(stroke
				(width 0.1)
				(type default)
			)
			(layer "B.Fab")
		)
		(fp_line
			(start 0.67945 0.3048)
			(end 0.67945 -0.305054)
			(stroke
				(width 0.1)
				(type default)
			)
			(layer "B.Fab")
		)
		(pad "1" smd circle
			(at 0.40005 0 180)
			(size 0 0)
			(layers "B.Cu" "B.Mask" "B.Paste")
			(net "PVDDCR_CPU1_P0")
		)
		(pad "2" smd circle
			(at -0.40005 0 180)
			(size 0 0)
			(layers "B.Cu" "B.Mask" "B.Paste")
			(net "GND")
		)
	)
)
